(kicad_pcb
	(version 20260206)
	(generator "pcbnew")
	(generator_version "10.0")
	(general
		(thickness 1.6)
		(legacy_teardrops no)
	)
	(paper "A4")
	(title_block
		(title "Bryce Canyon_F.DPB_16315-1-OCP.brd")
		(comment 1 "Bryce Canyon / footprints 664-670 of 2223")
	)
	(layers
		(0 "F.Cu" signal "TOP")
		(4 "In1.Cu" signal "L2GND")
		(6 "In2.Cu" signal "L3")
		(8 "In3.Cu" signal "L4GND")
		(10 "In4.Cu" signal "L5")
		(12 "In5.Cu" signal "L6VCC")
		(14 "In6.Cu" signal "L7VCC")
		(16 "In7.Cu" signal "L8")
		(18 "In8.Cu" signal "L9GND")
		(20 "In9.Cu" signal "L10")
		(22 "In10.Cu" signal "L11GND")
		(2 "B.Cu" signal "BOTTOM")
		(9 "F.Adhes" user "F.Adhesive")
		(11 "B.Adhes" user "B.Adhesive")
		(13 "F.Paste" user "Package Geometry/Pastemask Top")
		(15 "B.Paste" user "Package Geometry/Pastemask Bottom")
		(5 "F.SilkS" user "Ref Des/Silkscreen Top")
		(7 "B.SilkS" user "Ref Des/Silkscreen Bottom")
		(1 "F.Mask" user "Board Geometry/Soldermask Top")
		(3 "B.Mask" user "Board Geometry/Soldermask Bottom")
		(17 "Dwgs.User" user "User.Drawings")
		(19 "Cmts.User" user "User.Comments")
		(21 "Eco1.User" user "User.Eco1")
		(23 "Eco2.User" user "User.Eco2")
		(25 "Edge.Cuts" user "Board Geometry/Outline")
		(27 "Margin" user)
		(31 "F.CrtYd" user "Package Geometry/Place Bound Top")
		(29 "B.CrtYd" user "Package Geometry/Place Bound Bottom")
		(35 "F.Fab" user "Ref Des/Assembly Top")
		(33 "B.Fab" user "Ref Des/Assembly Bottom")
	)
	(footprint ""
		(layer "F.Cu")
		(at 17.800066 -209.399886)
		(property "Reference" "FLED1"
			(at 0 0 0)
			(layer "F.SilkS")
			(hide yes)
			(effects
				(font
					(size 1.27 1.27)
				)
			)
		)
		(property "Value" "LED-BY-19-GP"
			(at -2.132076 1.414018 0)
			(unlocked yes)
			(layer "F.Fab")
			(hide yes)
			(effects
				(font
					(size 1.016 1.016)
					(thickness 0.1524)
				)
			)
		)
		(property "Device Type" "LED-1615-4PH26"
			(at -2.132076 -0.109982 0)
			(unlocked yes)
			(layer "F.Fab")
			(hide yes)
			(effects
				(font
					(size 1.016 1.016)
					(thickness 0.1524)
				)
			)
		)
		(duplicate_pad_numbers_are_jumpers no)
		(fp_line
			(start -1.2954 0.254)
			(end -1.2954 1.6002)
			(stroke
				(width 0.508)
				(type default)
			)
			(layer "F.SilkS")
		)
		(fp_line
			(start -1.2954 1.6002)
			(end 1.2954 1.6002)
			(stroke
				(width 0.508)
				(type default)
			)
			(layer "F.SilkS")
		)
		(fp_line
			(start -1.1176 -1.4224)
			(end 1.1176 -1.4224)
			(stroke
				(width 0.1524)
				(type default)
			)
			(layer "F.SilkS")
		)
		(fp_line
			(start -1.1176 1.4224)
			(end -1.1176 -1.4224)
			(stroke
				(width 0.1524)
				(type default)
			)
			(layer "F.SilkS")
		)
		(fp_line
			(start 1.1176 -1.4224)
			(end 1.1176 1.4224)
			(stroke
				(width 0.1524)
				(type default)
			)
			(layer "F.SilkS")
		)
		(fp_line
			(start 1.1176 1.4224)
			(end -1.1176 1.4224)
			(stroke
				(width 0.1524)
				(type default)
			)
			(layer "F.SilkS")
		)
		(fp_line
			(start 1.2954 1.6002)
			(end 1.2954 0.254)
			(stroke
				(width 0.508)
				(type default)
			)
			(layer "F.SilkS")
		)
		(fp_rect
			(start -0.7493 0.8001)
			(end 0.7493 -0.8001)
			(stroke
				(width 0)
				(type default)
			)
			(fill no)
			(layer "F.CrtYd")
		)
		(fp_poly
			(pts
				(xy -1.3716 1.6764) (xy -1.3716 -1.6764) (xy 1.3716 -1.6764) (xy 1.3716 0.0635) (xy 0.7493 0.0635)
				(xy 0.7493 -0.8001) (xy -0.7493 -0.8001) (xy -0.7493 0.8001) (xy 0.7493 0.8001) (xy 0.7493 0.0762)
				(xy 1.3716 0.0762) (xy 1.3716 1.6764)
			)
			(stroke
				(width 0)
				(type default)
			)
			(fill no)
			(layer "F.CrtYd")
		)
		(fp_rect
			(start -1.3716 1.6764)
			(end 1.3716 -1.6764)
			(stroke
				(width 0)
				(type default)
			)
			(fill no)
			(layer "F.Fab")
		)
		(pad "1" smd rect
			(at 0.50038 -0.73025)
			(size 0.7112 0.8636)
			(layers "F.Cu" "F.Mask" "F.Paste")
			(net "DRV_ACT_0")
		)
		(pad "2" smd rect
			(at -0.50038 -0.73025)
			(size 0.7112 0.8636)
			(layers "F.Cu" "F.Mask" "F.Paste")
			(net "FLT_HDD0")
		)
		(pad "3" smd rect
			(at 0.50038 0.73025)
			(size 0.7112 0.8636)
			(layers "F.Cu" "F.Mask" "F.Paste")
			(net "DRV_ACT_0_N")
		)
		(pad "4" smd rect
			(at -0.50038 0.73025)
			(size 0.7112 0.8636)
			(layers "F.Cu" "F.Mask" "F.Paste")
			(net "FLT_HDD0_N")
		)
	)
	(footprint ""
		(layer "F.Cu")
		(at 141.042898 -174.857918)
		(property "Reference" "Q98"
			(at 0 0 0)
			(layer "F.SilkS")
			(hide yes)
			(effects
				(font
					(size 1.27 1.27)
				)
			)
		)
		(property "Value" "AO4407AL-GP"
			(at -3.707384 -1.5367 0)
			(unlocked yes)
			(layer "F.Fab")
			(hide yes)
			(effects
				(font
					(size 1.016 1.016)
					(thickness 0.1524)
				)
			)
		)
		(property "Device Type" "SOIC8H69"
			(at -3.707384 -3.0607 0)
			(unlocked yes)
			(layer "F.Fab")
			(hide yes)
			(effects
				(font
					(size 1.016 1.016)
					(thickness 0.1524)
				)
			)
		)
		(duplicate_pad_numbers_are_jumpers no)
		(fp_line
			(start -2.7432 -1.4224)
			(end -2.7432 1.4224)
			(stroke
				(width 0.1524)
				(type default)
			)
			(layer "F.SilkS")
		)
		(fp_line
			(start -2.7432 1.4224)
			(end -2.6416 1.4224)
			(stroke
				(width 0.1524)
				(type default)
			)
			(layer "F.SilkS")
		)
		(fp_line
			(start -2.7432 1.4224)
			(end 2.1336 1.4224)
			(stroke
				(width 0.1524)
				(type default)
			)
			(layer "F.SilkS")
		)
		(fp_line
			(start -2.7178 -0.508)
			(end -2.1844 -0.0508)
			(stroke
				(width 0.1524)
				(type default)
			)
			(layer "F.SilkS")
		)
		(fp_line
			(start -2.6289 3.4417)
			(end -2.6289 1.4732)
			(stroke
				(width 0.381)
				(type default)
			)
			(layer "F.SilkS")
		)
		(fp_line
			(start -2.1844 -0.0508)
			(end -2.7178 0.508)
			(stroke
				(width 0.1524)
				(type default)
			)
			(layer "F.SilkS")
		)
		(fp_line
			(start 2.1336 -1.4224)
			(end -2.7432 -1.4224)
			(stroke
				(width 0.1524)
				(type default)
			)
			(layer "F.SilkS")
		)
		(fp_line
			(start 2.1336 1.4224)
			(end 2.1336 -1.4224)
			(stroke
				(width 0.1524)
				(type default)
			)
			(layer "F.SilkS")
		)
		(fp_poly
			(pts
				(xy -2.2098 -1.4224) (xy -2.2098 1.4224) (xy 2.2098 1.4224) (xy 2.2098 -1.4224)
			)
			(stroke
				(width 0)
				(type default)
			)
			(fill yes)
			(layer "F.SilkS")
		)
		(fp_rect
			(start -2.450084 2.999994)
			(end 2.450084 -2.999994)
			(stroke
				(width 0)
				(type default)
			)
			(fill no)
			(layer "F.CrtYd")
		)
		(fp_poly
			(pts
				(xy -2.8194 3.6322) (xy -2.8194 -3.6322) (xy 2.8194 -3.6322) (xy 2.8194 1.18364) (xy 2.450084 1.18364)
				(xy 2.450084 -2.999994) (xy -2.450084 -2.999994) (xy -2.450084 2.999994) (xy 2.450084 2.999994)
				(xy 2.450084 1.18618) (xy 2.8194 1.18618) (xy 2.8194 3.6322)
			)
			(stroke
				(width 0)
				(type default)
			)
			(fill no)
			(layer "F.CrtYd")
		)
		(fp_rect
			(start -2.8194 3.6322)
			(end 2.8194 -3.6322)
			(stroke
				(width 0)
				(type default)
			)
			(fill no)
			(layer "F.Fab")
		)
		(pad "1" smd rect
			(at -1.905 2.54)
			(size 0.635 1.651)
			(layers "F.Cu" "F.Mask" "F.Paste")
			(net "P12V_A")
		)
		(pad "2" smd rect
			(at -0.635 2.54)
			(size 0.635 1.651)
			(layers "F.Cu" "F.Mask" "F.Paste")
			(net "P12V_A")
		)
		(pad "3" smd rect
			(at 0.635 2.54)
			(size 0.635 1.651)
			(layers "F.Cu" "F.Mask" "F.Paste")
			(net "P12V_A")
		)
		(pad "4" smd rect
			(at 1.905 2.54)
			(size 0.635 1.651)
			(layers "F.Cu" "F.Mask" "F.Paste")
			(net "SW_HDD_N16")
		)
		(pad "5" smd rect
			(at 1.905 -2.54)
			(size 0.635 1.651)
			(layers "F.Cu" "F.Mask" "F.Paste")
			(net "P12V_HDD16")
		)
		(pad "6" smd rect
			(at 0.635 -2.54)
			(size 0.635 1.651)
			(layers "F.Cu" "F.Mask" "F.Paste")
			(net "P12V_HDD16")
		)
		(pad "7" smd rect
			(at -0.635 -2.54)
			(size 0.635 1.651)
			(layers "F.Cu" "F.Mask" "F.Paste")
			(net "P12V_HDD16")
		)
		(pad "8" smd rect
			(at -1.905 -2.54)
			(size 0.635 1.651)
			(layers "F.Cu" "F.Mask" "F.Paste")
			(net "P12V_HDD16")
		)
	)
	(footprint ""
		(layer "F.Cu")
		(at 428.152052 -303.954942 180)
		(property "Reference" "C162"
			(at 0 0 180)
			(layer "F.SilkS")
			(hide yes)
			(effects
				(font
					(size 1.27 1.27)
				)
			)
		)
		(property "Value" "SC4D7U25V5KX-1-GP"
			(at -0.0762 -6.1214 180)
			(unlocked yes)
			(layer "F.Fab")
			(hide yes)
			(effects
				(font
					(size 1.016 1.016)
					(thickness 0.1524)
				)
			)
		)
		(property "Device Type" "C805H58"
			(at -0.0762 -8.1534 180)
			(unlocked yes)
			(layer "F.Fab")
			(hide yes)
			(effects
				(font
					(size 1.016 1.016)
					(thickness 0.1524)
				)
			)
		)
		(duplicate_pad_numbers_are_jumpers no)
		(fp_line
			(start 0.635 0)
			(end -0.635 0)
			(stroke
				(width 0.508)
				(type default)
			)
			(layer "F.SilkS")
		)
		(fp_rect
			(start -0.9652 1.778)
			(end 0.9652 -1.778)
			(stroke
				(width 0)
				(type default)
			)
			(fill no)
			(layer "F.CrtYd")
		)
		(fp_poly
			(pts
				(xy -0.9652 -1.778) (xy 0.9652 -1.778) (xy 0.9652 1.778) (xy -0.9652 1.778)
			)
			(stroke
				(width 0)
				(type default)
			)
			(fill no)
			(layer "F.Fab")
		)
		(pad "1" smd rect
			(at 0 -0.9652 180)
			(size 1.397 1.143)
			(layers "F.Cu" "F.Mask" "F.Paste")
			(net "P12V_HDD9")
		)
		(pad "2" smd rect
			(at 0 0.9652 180)
			(size 1.397 1.143)
			(layers "F.Cu" "F.Mask" "F.Paste")
			(net "GND")
		)
	)
	(footprint ""
		(layer "F.Cu")
		(at 460.355442 -184.345072 -90)
		(property "Reference" "R637"
			(at 0 0 270)
			(layer "F.SilkS")
			(hide yes)
			(effects
				(font
					(size 1.27 1.27)
				)
			)
		)
		(property "Value" "2R6F-GP"
			(at -0.0508 -4.8514 270)
			(unlocked yes)
			(layer "F.Fab")
			(hide yes)
			(effects
				(font
					(size 1.016 1.016)
					(thickness 0.1524)
				)
			)
		)
		(property "Device Type" "R1206H26"
			(at 0 -6.3754 270)
			(unlocked yes)
			(layer "F.Fab")
			(hide yes)
			(effects
				(font
					(size 1.016 1.016)
					(thickness 0.1524)
				)
			)
		)
		(duplicate_pad_numbers_are_jumpers no)
		(fp_line
			(start -1.016 2.2352)
			(end -1.016 -2.2352)
			(stroke
				(width 0.1524)
				(type default)
			)
			(layer "F.SilkS")
		)
		(fp_line
			(start 1.016 2.2352)
			(end -1.016 2.2352)
			(stroke
				(width 0.1524)
				(type default)
			)
			(layer "F.SilkS")
		)
		(fp_line
			(start -1.016 -2.2352)
			(end 1.016 -2.2352)
			(stroke
				(width 0.1524)
				(type default)
			)
			(layer "F.SilkS")
		)
		(fp_line
			(start 1.016 -2.2352)
			(end 1.016 2.2352)
			(stroke
				(width 0.1524)
				(type default)
			)
			(layer "F.SilkS")
		)
		(fp_rect
			(start -1.0922 2.3114)
			(end 1.0922 -2.3114)
			(stroke
				(width 0)
				(type default)
			)
			(fill no)
			(layer "F.CrtYd")
		)
		(fp_poly
			(pts
				(xy -1.0922 -2.3114) (xy 1.0922 -2.3114) (xy 1.0922 2.3114) (xy -1.0922 2.3114)
			)
			(stroke
				(width 0)
				(type default)
			)
			(fill no)
			(layer "F.Fab")
		)
		(pad "1" smd rect
			(at 0 -1.397 270)
			(size 1.651 1.27)
			(layers "F.Cu" "F.Mask" "F.Paste")
			(net "P12V_HDD22")
		)
		(pad "2" smd rect
			(at 0 1.397 270)
			(size 1.651 1.27)
			(layers "F.Cu" "F.Mask" "F.Paste")
			(net "12V_PRE_22")
		)
	)
	(footprint ""
		(layer "F.Cu")
		(at 38.654228 -301.29988 90)
		(property "Reference" "R564"
			(at 0 0 90)
			(layer "F.SilkS")
			(hide yes)
			(effects
				(font
					(size 1.27 1.27)
				)
			)
		)
		(property "Value" "4K7R2J-2-GP"
			(at 0.064008 -3.993896 90)
			(unlocked yes)
			(layer "F.Fab")
			(hide yes)
			(effects
				(font
					(size 1.016 1.016)
					(thickness 0.1524)
				)
			)
		)
		(property "Device Type" "R402H16"
			(at 0.064008 -5.517896 90)
			(unlocked yes)
			(layer "F.Fab")
			(hide yes)
			(effects
				(font
					(size 1.016 1.016)
					(thickness 0.1524)
				)
			)
		)
		(duplicate_pad_numbers_are_jumpers no)
		(fp_line
			(start 0.508 -0.9398)
			(end -0.508 -0.9398)
			(stroke
				(width 0.1524)
				(type default)
			)
			(layer "F.SilkS")
		)
		(fp_line
			(start -0.508 -0.9398)
			(end -0.508 0.9398)
			(stroke
				(width 0.1524)
				(type default)
			)
			(layer "F.SilkS")
		)
		(fp_rect
			(start -0.508 0.9398)
			(end 0.508 -0.9398)
			(stroke
				(width 0)
				(type default)
			)
			(fill no)
			(layer "F.CrtYd")
		)
		(fp_rect
			(start -0.508 0.9398)
			(end 0.508 -0.9398)
			(stroke
				(width 0)
				(type default)
			)
			(fill no)
			(layer "F.Fab")
		)
		(pad "1" smd custom
			(at 0 -0.4445 90)
			(size 0.1397 0.1397)
			(layers "F.Cu" "F.Mask" "F.Paste")
			(net "DRIVE_B_25_FLT_LED")
			(options
				(clearance outline)
				(anchor circle)
			)
			(primitives
				(gr_poly
					(pts
						(arc
							(start -0.1778 -0.2794)
							(mid -0.249642 -0.249642)
							(end -0.2794 -0.1778)
						)
						(arc
							(start -0.2794 0.1778)
							(mid -0.249642 0.249642)
							(end -0.1778 0.2794)
						)
						(arc
							(start 0.1778 0.2794)
							(mid 0.249642 0.249642)
							(end 0.2794 0.1778)
						)
						(arc
							(start 0.2794 -0.1778)
							(mid 0.249642 -0.249642)
							(end 0.1778 -0.2794)
						)
					)
					(width 0)
					(fill yes)
				)
			)
		)
		(pad "2" smd custom
			(at 0 0.4445 90)
			(size 0.1397 0.1397)
			(layers "F.Cu" "F.Mask" "F.Paste")
			(net "GND")
			(options
				(clearance outline)
				(anchor circle)
			)
			(primitives
				(gr_poly
					(pts
						(arc
							(start -0.1778 -0.2794)
							(mid -0.249642 -0.249642)
							(end -0.2794 -0.1778)
						)
						(arc
							(start -0.2794 0.1778)
							(mid -0.249642 0.249642)
							(end -0.1778 0.2794)
						)
						(arc
							(start 0.1778 0.2794)
							(mid 0.249642 0.249642)
							(end 0.2794 0.1778)
						)
						(arc
							(start 0.2794 -0.1778)
							(mid 0.249642 -0.249642)
							(end 0.1778 -0.2794)
						)
					)
					(width 0)
					(fill yes)
				)
			)
		)
	)
	(footprint ""
		(layer "F.Cu")
		(at 150.943818 -135.22198)
		(property "Reference" "R1037"
			(at 0 0 0)
			(layer "F.SilkS")
			(hide yes)
			(effects
				(font
					(size 1.27 1.27)
				)
			)
		)
		(property "Value" "100R2D-GP"
			(at 0.064008 -3.993896 0)
			(unlocked yes)
			(layer "F.Fab")
			(hide yes)
			(effects
				(font
					(size 1.016 1.016)
					(thickness 0.1524)
				)
			)
		)
		(property "Device Type" "R402H14"
			(at 0.064008 -5.517896 0)
			(unlocked yes)
			(layer "F.Fab")
			(hide yes)
			(effects
				(font
					(size 1.016 1.016)
					(thickness 0.1524)
				)
			)
		)
		(duplicate_pad_numbers_are_jumpers no)
		(fp_line
			(start -0.508 -0.9398)
			(end -0.508 0.9398)
			(stroke
				(width 0.1524)
				(type default)
			)
			(layer "F.SilkS")
		)
		(fp_line
			(start 0.508 -0.9398)
			(end -0.508 -0.9398)
			(stroke
				(width 0.1524)
				(type default)
			)
			(layer "F.SilkS")
		)
		(fp_rect
			(start -0.508 0.9398)
			(end 0.508 -0.9398)
			(stroke
				(width 0)
				(type default)
			)
			(fill no)
			(layer "F.CrtYd")
		)
		(fp_rect
			(start -0.508 0.9398)
			(end 0.508 -0.9398)
			(stroke
				(width 0)
				(type default)
			)
			(fill no)
			(layer "F.Fab")
		)
		(pad "1" smd custom
			(at 0 -0.4445)
			(size 0.1397 0.1397)
			(layers "F.Cu" "F.Mask" "F.Paste")
			(net "MB0_TEMP")
			(options
				(clearance outline)
				(anchor circle)
			)
			(primitives
				(gr_poly
					(pts
						(arc
							(start -0.1778 -0.2794)
							(mid -0.249642 -0.249642)
							(end -0.2794 -0.1778)
						)
						(arc
							(start -0.2794 0.1778)
							(mid -0.249642 0.249642)
							(end -0.1778 0.2794)
						)
						(arc
							(start 0.1778 0.2794)
							(mid 0.249642 0.249642)
							(end 0.2794 0.1778)
						)
						(arc
							(start 0.2794 -0.1778)
							(mid 0.249642 -0.249642)
							(end 0.1778 -0.2794)
						)
					)
					(width 0)
					(fill yes)
				)
			)
		)
		(pad "2" smd custom
			(at 0 0.4445)
			(size 0.1397 0.1397)
			(layers "F.Cu" "F.Mask" "F.Paste")
			(net "MB0_TEMP_B")
			(options
				(clearance outline)
				(anchor circle)
			)
			(primitives
				(gr_poly
					(pts
						(arc
							(start -0.1778 -0.2794)
							(mid -0.249642 -0.249642)
							(end -0.2794 -0.1778)
						)
						(arc
							(start -0.2794 0.1778)
							(mid -0.249642 0.249642)
							(end -0.1778 0.2794)
						)
						(arc
							(start 0.1778 0.2794)
							(mid 0.249642 0.249642)
							(end 0.2794 0.1778)
						)
						(arc
							(start 0.2794 -0.1778)
							(mid 0.249642 -0.249642)
							(end 0.1778 -0.2794)
						)
					)
					(width 0)
					(fill yes)
				)
			)
		)
	)
	(footprint ""
		(layer "F.Cu")
		(at 261.932166 -338.052664 90)
		(property "Reference" "R388"
			(at 0 0 90)
			(layer "F.SilkS")
			(hide yes)
			(effects
				(font
					(size 1.27 1.27)
				)
			)
		)
		(property "Value" "10KR2F-2-GP"
			(at 0.064008 -3.993896 90)
			(unlocked yes)
			(layer "F.Fab")
			(hide yes)
			(effects
				(font
					(size 1.016 1.016)
					(thickness 0.1524)
				)
			)
		)
		(property "Device Type" "R402H16"
			(at 0.064008 -5.517896 90)
			(unlocked yes)
			(layer "F.Fab")
			(hide yes)
			(effects
				(font
					(size 1.016 1.016)
					(thickness 0.1524)
				)
			)
		)
		(duplicate_pad_numbers_are_jumpers no)
		(fp_line
			(start 0.508 -0.9398)
			(end -0.508 -0.9398)
			(stroke
				(width 0.1524)
				(type default)
			)
			(layer "F.SilkS")
		)
		(fp_line
			(start -0.508 -0.9398)
			(end -0.508 0.9398)
			(stroke
				(width 0.1524)
				(type default)
			)
			(layer "F.SilkS")
		)
		(fp_rect
			(start -0.508 0.9398)
			(end 0.508 -0.9398)
			(stroke
				(width 0)
				(type default)
			)
			(fill no)
			(layer "F.CrtYd")
		)
		(fp_rect
			(start -0.508 0.9398)
			(end 0.508 -0.9398)
			(stroke
				(width 0)
				(type default)
			)
			(fill no)
			(layer "F.Fab")
		)
		(pad "1" smd custom
			(at 0 -0.4445 90)
			(size 0.1397 0.1397)
			(layers "F.Cu" "F.Mask" "F.Paste")
			(net "P3V3_STBY_A")
			(options
				(clearance outline)
				(anchor circle)
			)
			(primitives
				(gr_poly
					(pts
						(arc
							(start -0.1778 -0.2794)
							(mid -0.249642 -0.249642)
							(end -0.2794 -0.1778)
						)
						(arc
							(start -0.2794 0.1778)
							(mid -0.249642 0.249642)
							(end -0.1778 0.2794)
						)
						(arc
							(start 0.1778 0.2794)
							(mid 0.249642 0.249642)
							(end 0.2794 0.1778)
						)
						(arc
							(start 0.2794 -0.1778)
							(mid 0.249642 -0.249642)
							(end 0.1778 -0.2794)
						)
					)
					(width 0)
					(fill yes)
				)
			)
		)
		(pad "2" smd custom
			(at 0 0.4445 90)
			(size 0.1397 0.1397)
			(layers "F.Cu" "F.Mask" "F.Paste")
			(net "SCC_A_TYPE_3")
			(options
				(clearance outline)
				(anchor circle)
			)
			(primitives
				(gr_poly
					(pts
						(arc
							(start -0.1778 -0.2794)
							(mid -0.249642 -0.249642)
							(end -0.2794 -0.1778)
						)
						(arc
							(start -0.2794 0.1778)
							(mid -0.249642 0.249642)
							(end -0.1778 0.2794)
						)
						(arc
							(start 0.1778 0.2794)
							(mid 0.249642 0.249642)
							(end 0.2794 0.1778)
						)
						(arc
							(start 0.2794 -0.1778)
							(mid 0.249642 -0.249642)
							(end 0.1778 -0.2794)
						)
					)
					(width 0)
					(fill yes)
				)
			)
		)
	)
)
